# SCM (Grand Teton) — schematic netlist excerpt (pin names and nets, part order shuffled) for the footprints in the layout excerpt that follows; sources: Cadence DE-HDL packaged netlist, KiCad conversion of 12092022_DA0F0TMDCD0_F0T_Management_Board_D_brd_V3_OCP.brd

R23  Q_RES  150 1% CHIP  pkg 0402LF  page 15 : A = V_DACG_R ; B = GND
R614  Q_RES  100K 1% CHIP  pkg 0402LF  page 22 : A = RST_SRST_PLD_BMC_R1_N ; B = GND

(kicad_pcb
	(version 20260206)
	(generator "pcbnew")
	(generator_version "10.0")
	(general
		(thickness 1.6)
		(legacy_teardrops no)
	)
	(paper "A4")
	(title_block
		(title "12092022_DA0F0TMDCD0_F0T_Management_Board_D_brd_V3_OCP.brd")
		(comment 1 "Grand Teton / footprints 99-100 of 1440")
	)
	(layers
		(0 "F.Cu" signal "TOP")
		(4 "In1.Cu" signal "GND")
		(6 "In2.Cu" signal "IN1")
		(8 "In3.Cu" signal "GND1")
		(10 "In4.Cu" signal "IN2")
		(12 "In5.Cu" signal "VCC")
		(14 "In6.Cu" signal "VCC1")
		(16 "In7.Cu" signal "IN3")
		(18 "In8.Cu" signal "GND2")
		(20 "In9.Cu" signal "IN4")
		(22 "In10.Cu" signal "GND3")
		(2 "B.Cu" signal "BOTTOM")
		(9 "F.Adhes" user "F.Adhesive")
		(11 "B.Adhes" user "B.Adhesive")
		(13 "F.Paste" user "Package Geometry/Pastemask Top")
		(15 "B.Paste" user "Package Geometry/Pastemask Bottom")
		(5 "F.SilkS" user "Ref Des/Silkscreen Top")
		(7 "B.SilkS" user "Ref Des/Silkscreen Bottom")
		(1 "F.Mask" user "Board Geometry/Soldermask Top")
		(3 "B.Mask" user "Board Geometry/Soldermask Bottom")
		(17 "Dwgs.User" user "User.Drawings")
		(19 "Cmts.User" user "User.Comments")
		(21 "Eco1.User" user "User.Eco1")
		(23 "Eco2.User" user "User.Eco2")
		(25 "Edge.Cuts" user "Board Geometry/Outline")
		(27 "Margin" user)
		(31 "F.CrtYd" user "Package Geometry/Place Bound Top")
		(29 "B.CrtYd" user "Package Geometry/Place Bound Bottom")
		(35 "F.Fab" user "Ref Des/Assembly Top")
		(33 "B.Fab" user "Ref Des/Assembly Bottom")
	)
	(footprint ""
		(layer "F.Cu")
		(at 5.334 -80.899 -90)
		(property "Reference" "R614"
			(at 0 0 270)
			(layer "F.SilkS")
			(hide yes)
			(effects
				(font
					(size 1.27 1.27)
				)
			)
		)
		(property "Value" ""
			(at 0 0 270)
			(layer "F.Fab")
			(effects
				(font
					(size 1.27 1.27)
				)
			)
		)
		(duplicate_pad_numbers_are_jumpers no)
		(fp_line
			(start -0.7874 0.4064)
			(end -0.7874 -0.4064)
			(stroke
				(width 0.1524)
				(type default)
			)
			(layer "F.SilkS")
		)
		(fp_line
			(start 0.7874 0.4064)
			(end -0.7874 0.4064)
			(stroke
				(width 0.1524)
				(type default)
			)
			(layer "F.SilkS")
		)
		(fp_line
			(start -0.7874 -0.4064)
			(end 0.7874 -0.4064)
			(stroke
				(width 0.1524)
				(type default)
			)
			(layer "F.SilkS")
		)
		(fp_line
			(start 0.7874 -0.4064)
			(end 0.7874 0.4064)
			(stroke
				(width 0.1524)
				(type default)
			)
			(layer "F.SilkS")
		)
		(fp_line
			(start -0.67945 0.3048)
			(end -0.67945 -0.305054)
			(stroke
				(width 0.1)
				(type default)
			)
			(layer "F.Fab")
		)
		(fp_line
			(start -0.12065 0.3048)
			(end -0.67945 0.3048)
			(stroke
				(width 0.1)
				(type default)
			)
			(layer "F.Fab")
		)
		(fp_line
			(start 0.120396 0.3048)
			(end 0.120396 0.2794)
			(stroke
				(width 0.1)
				(type default)
			)
			(layer "F.Fab")
		)
		(fp_line
			(start 0.67945 0.3048)
			(end 0.120396 0.3048)
			(stroke
				(width 0.1)
				(type default)
			)
			(layer "F.Fab")
		)
		(fp_line
			(start -0.12065 0.2794)
			(end -0.12065 0.3048)
			(stroke
				(width 0.1)
				(type default)
			)
			(layer "F.Fab")
		)
		(fp_line
			(start 0.120396 0.2794)
			(end -0.12065 0.2794)
			(stroke
				(width 0.1)
				(type default)
			)
			(layer "F.Fab")
		)
		(fp_line
			(start -0.12065 -0.2794)
			(end 0.12065 -0.2794)
			(stroke
				(width 0.1)
				(type default)
			)
			(layer "F.Fab")
		)
		(fp_line
			(start 0.12065 -0.2794)
			(end 0.12065 -0.3048)
			(stroke
				(width 0.1)
				(type default)
			)
			(layer "F.Fab")
		)
		(fp_line
			(start 0.12065 -0.3048)
			(end 0.67945 -0.3048)
			(stroke
				(width 0.1)
				(type default)
			)
			(layer "F.Fab")
		)
		(fp_line
			(start 0.67945 -0.3048)
			(end 0.67945 0.3048)
			(stroke
				(width 0.1)
				(type default)
			)
			(layer "F.Fab")
		)
		(fp_line
			(start -0.67945 -0.305054)
			(end -0.12065 -0.305054)
			(stroke
				(width 0.1)
				(type default)
			)
			(layer "F.Fab")
		)
		(fp_line
			(start -0.12065 -0.305054)
			(end -0.12065 -0.2794)
			(stroke
				(width 0.1)
				(type default)
			)
			(layer "F.Fab")
		)
		(pad "1" smd circle
			(at -0.40005 0 270)
			(size 0 0)
			(layers "F.Cu" "F.Mask" "F.Paste")
			(net "RST_SRST_PLD_BMC_R1_N")
		)
		(pad "2" smd circle
			(at 0.40005 0 270)
			(size 0 0)
			(layers "F.Cu" "F.Mask" "F.Paste")
			(net "GND")
		)
	)
	(footprint ""
		(layer "F.Cu")
		(at 45.062902 -63.756794 -90)
		(property "Reference" "R23"
			(at 0 0 270)
			(layer "F.SilkS")
			(hide yes)
			(effects
				(font
					(size 1.27 1.27)
				)
			)
		)
		(property "Value" ""
			(at 0 0 270)
			(layer "F.Fab")
			(effects
				(font
					(size 1.27 1.27)
				)
			)
		)
		(duplicate_pad_numbers_are_jumpers no)
		(fp_line
			(start -0.7874 0.4064)
			(end -0.7874 -0.4064)
			(stroke
				(width 0.1524)
				(type default)
			)
			(layer "F.SilkS")
		)
		(fp_line
			(start 0.7874 0.4064)
			(end -0.7874 0.4064)
			(stroke
				(width 0.1524)
				(type default)
			)
			(layer "F.SilkS")
		)
		(fp_line
			(start -0.7874 -0.4064)
			(end 0.7874 -0.4064)
			(stroke
				(width 0.1524)
				(type default)
			)
			(layer "F.SilkS")
		)
		(fp_line
			(start 0.7874 -0.4064)
			(end 0.7874 0.4064)
			(stroke
				(width 0.1524)
				(type default)
			)
			(layer "F.SilkS")
		)
		(fp_line
			(start -0.67945 0.3048)
			(end -0.67945 -0.305054)
			(stroke
				(width 0.1)
				(type default)
			)
			(layer "F.Fab")
		)
		(fp_line
			(start -0.12065 0.3048)
			(end -0.67945 0.3048)
			(stroke
				(width 0.1)
				(type default)
			)
			(layer "F.Fab")
		)
		(fp_line
			(start 0.120396 0.3048)
			(end 0.120396 0.2794)
			(stroke
				(width 0.1)
				(type default)
			)
			(layer "F.Fab")
		)
		(fp_line
			(start 0.67945 0.3048)
			(end 0.120396 0.3048)
			(stroke
				(width 0.1)
				(type default)
			)
			(layer "F.Fab")
		)
		(fp_line
			(start -0.12065 0.2794)
			(end -0.12065 0.3048)
			(stroke
				(width 0.1)
				(type default)
			)
			(layer "F.Fab")
		)
		(fp_line
			(start 0.120396 0.2794)
			(end -0.12065 0.2794)
			(stroke
				(width 0.1)
				(type default)
			)
			(layer "F.Fab")
		)
		(fp_line
			(start -0.12065 -0.2794)
			(end 0.12065 -0.2794)
			(stroke
				(width 0.1)
				(type default)
			)
			(layer "F.Fab")
		)
		(fp_line
			(start 0.12065 -0.2794)
			(end 0.12065 -0.3048)
			(stroke
				(width 0.1)
				(type default)
			)
			(layer "F.Fab")
		)
		(fp_line
			(start 0.12065 -0.3048)
			(end 0.67945 -0.3048)
			(stroke
				(width 0.1)
				(type default)
			)
			(layer "F.Fab")
		)
		(fp_line
			(start 0.67945 -0.3048)
			(end 0.67945 0.3048)
			(stroke
				(width 0.1)
				(type default)
			)
			(layer "F.Fab")
		)
		(fp_line
			(start -0.67945 -0.305054)
			(end -0.12065 -0.305054)
			(stroke
				(width 0.1)
				(type default)
			)
			(layer "F.Fab")
		)
		(fp_line
			(start -0.12065 -0.305054)
			(end -0.12065 -0.2794)
			(stroke
				(width 0.1)
				(type default)
			)
			(layer "F.Fab")
		)
		(pad "1" smd circle
			(at -0.40005 0 270)
			(size 0 0)
			(layers "F.Cu" "F.Mask" "F.Paste")
			(net "V_DACG_R")
		)
		(pad "2" smd circle
			(at 0.40005 0 270)
			(size 0 0)
			(layers "F.Cu" "F.Mask" "F.Paste")
			(net "GND")
		)
	)
)
